#ISCELL
  pure_quanta quanta_title_block_c *
  *
#CELL
  pure_quanta q_cap *
  page164_i1
#CELL
  pure_quanta q_cap *
  page164_i10
#ISCELL
  pure_quanta_power universal_power *
  page164_i11
#CELL
  pure_quanta q_cap *
  page164_i12
#CELL
  pure_quanta q_cap *
  page164_i13
#ISCELL
  standard offpage *
  page164_i14
#CELL
  pure_quanta q_res *
  page164_i15
#CELL
  pure_quanta mpq8633aglec807z *
  page164_i16
#ISCELL
  pure_quanta_power gnd *
  page164_i17
#CELL
  pure_quanta q_cap *
  page164_i18
#ISCELL
  pure_quanta_power gnd *
  page164_i19
#ISCELL
  pure_quanta_power gnd *
  page164_i2
#ISCELL
  pure_quanta_power gnd *
  page164_i20
#ISCELL
  pure_quanta_power gnd *
  page164_i21
#ISCELL
  pure_quanta_power gnd *
  page164_i22
#CELL
  pure_quanta q_cap *
  page164_i23
#CELL
  pure_quanta q_res *
  page164_i24
#CELL
  pure_quanta q_cap *
  page164_i25
#CELL
  pure_quanta q_res *
  page164_i26
#CELL
  pure_quanta q_res *
  page164_i27
#CELL
  pure_quanta q_cap *
  page164_i28
#CELL
  pure_quanta q_res *
  page164_i29
#ISCELL
  pure_quanta_power p1v0_aux *
  page164_i3
#CELL
  pure_quanta q_inductor *
  page164_i30
#CELL
  pure_quanta q_capp *
  page164_i31
#ISCELL
  standard offpage *
  page164_i32
#ISCELL
  pure_quanta_power universal_power *
  page164_i33
#CELL
  pure_quanta q_cap *
  page164_i34
#CELL
  pure_quanta q_cap *
  page164_i35
#ISCELL
  pure_quanta_power gnd *
  page164_i36
#CELL
  pure_quanta q_cap *
  page164_i37
#ISCELL
  pure_quanta_power p1v0 *
  page164_i38
#CELL
  pure_quanta q_inductor *
  page164_i4
#ISCELL
  pure_quanta_power gnd *
  page164_i5
#CELL
  pure_quanta q_cap *
  page164_i6
#ISCELL
  pure_quanta_power gnd *
  page164_i7
#ISCELL
  pure_quanta_power gnd *
  page164_i8
#CELL
  pure_quanta q_res *
  page164_i9
